# S9S_MB_2U (Grand Teton) — schematic netlist excerpt (pin names and nets, part order shuffled) for the footprints in the layout excerpt that follows; sources: Cadence DE-HDL packaged netlist, KiCad conversion of 03242023_DA0F0TMBIJ0_F0T_Motherboard_J_brd_V01_OCP.brd

PR699  Q_RES  0 5% EMPTY  pkg 0402LF  page 294 : A = P3V3 ; B = PVCCFA_EHV_CPU1_PVCC
C327  Q_CAP  47UF 4V 20% X6S  pkg C0805  page 78 : A = PVCCIN_CPU1 ; B = GND
PR3335  Q_RES  30.1K 1% CHIP  pkg 0402LF  page 281 : A = PVPP_HBM_CPU0_MODE ; B = GND

(kicad_pcb
	(version 20260206)
	(generator "pcbnew")
	(generator_version "10.0")
	(general
		(thickness 1.6)
		(legacy_teardrops no)
	)
	(paper "A4")
	(title_block
		(title "03242023_DA0F0TMBIJ0_F0T_Motherboard_J_brd_V01_OCP.brd")
		(comment 1 "Grand Teton / footprints 4960-4962 of 6105")
	)
	(layers
		(0 "F.Cu" signal "TOP")
		(4 "In1.Cu" signal "GND")
		(6 "In2.Cu" signal "IN1")
		(8 "In3.Cu" signal "GND1")
		(10 "In4.Cu" signal "IN2")
		(12 "In5.Cu" signal "GND2")
		(14 "In6.Cu" signal "IN3")
		(16 "In7.Cu" signal "GND3")
		(18 "In8.Cu" signal "VCC")
		(20 "In9.Cu" signal "VCC1")
		(22 "In10.Cu" signal "GND4")
		(24 "In11.Cu" signal "IN4")
		(26 "In12.Cu" signal "GND5")
		(28 "In13.Cu" signal "IN5")
		(30 "In14.Cu" signal "GND6")
		(32 "In15.Cu" signal "IN6")
		(34 "In16.Cu" signal "GND7")
		(2 "B.Cu" signal "BOTTOM")
		(9 "F.Adhes" user "F.Adhesive")
		(11 "B.Adhes" user "B.Adhesive")
		(13 "F.Paste" user "Package Geometry/Pastemask Top")
		(15 "B.Paste" user "Package Geometry/Pastemask Bottom")
		(5 "F.SilkS" user "Ref Des/Silkscreen Top")
		(7 "B.SilkS" user "Ref Des/Silkscreen Bottom")
		(1 "F.Mask" user "Board Geometry/Soldermask Top")
		(3 "B.Mask" user "Board Geometry/Soldermask Bottom")
		(17 "Dwgs.User" user "User.Drawings")
		(19 "Cmts.User" user "User.Comments")
		(21 "Eco1.User" user "User.Eco1")
		(23 "Eco2.User" user "User.Eco2")
		(25 "Edge.Cuts" user "Board Geometry/Outline")
		(27 "Margin" user)
		(31 "F.CrtYd" user "Package Geometry/Place Bound Top")
		(29 "B.CrtYd" user "Package Geometry/Place Bound Bottom")
		(35 "F.Fab" user "Ref Des/Assembly Top")
		(33 "B.Fab" user "Ref Des/Assembly Bottom")
	)
	(footprint ""
		(layer "B.Cu")
		(at 372.299738 -359.50271 -90)
		(property "Reference" "PR3335"
			(at 0 0 90)
			(layer "B.SilkS")
			(hide yes)
			(effects
				(font
					(size 1.27 1.27)
				)
				(justify mirror)
			)
		)
		(property "Value" ""
			(at 0 0 90)
			(layer "B.Fab")
			(effects
				(font
					(size 1.27 1.27)
				)
				(justify mirror)
			)
		)
		(duplicate_pad_numbers_are_jumpers no)
		(fp_line
			(start -0.7874 0.4064)
			(end 0.7874 0.4064)
			(stroke
				(width 0.1524)
				(type default)
			)
			(layer "B.SilkS")
		)
		(fp_line
			(start 0.7874 0.4064)
			(end 0.7874 -0.4064)
			(stroke
				(width 0.1524)
				(type default)
			)
			(layer "B.SilkS")
		)
		(fp_line
			(start -0.7874 -0.4064)
			(end -0.7874 0.4064)
			(stroke
				(width 0.1524)
				(type default)
			)
			(layer "B.SilkS")
		)
		(fp_line
			(start 0.7874 -0.4064)
			(end -0.7874 -0.4064)
			(stroke
				(width 0.1524)
				(type default)
			)
			(layer "B.SilkS")
		)
		(fp_line
			(start -0.67945 0.3048)
			(end -0.120396 0.3048)
			(stroke
				(width 0.1)
				(type default)
			)
			(layer "B.Fab")
		)
		(fp_line
			(start -0.120396 0.3048)
			(end -0.120396 0.2794)
			(stroke
				(width 0.1)
				(type default)
			)
			(layer "B.Fab")
		)
		(fp_line
			(start 0.12065 0.3048)
			(end 0.67945 0.3048)
			(stroke
				(width 0.1)
				(type default)
			)
			(layer "B.Fab")
		)
		(fp_line
			(start 0.67945 0.3048)
			(end 0.67945 -0.305054)
			(stroke
				(width 0.1)
				(type default)
			)
			(layer "B.Fab")
		)
		(fp_line
			(start -0.120396 0.2794)
			(end 0.12065 0.2794)
			(stroke
				(width 0.1)
				(type default)
			)
			(layer "B.Fab")
		)
		(fp_line
			(start 0.12065 0.2794)
			(end 0.12065 0.3048)
			(stroke
				(width 0.1)
				(type default)
			)
			(layer "B.Fab")
		)
		(fp_line
			(start -0.12065 -0.2794)
			(end -0.12065 -0.3048)
			(stroke
				(width 0.1)
				(type default)
			)
			(layer "B.Fab")
		)
		(fp_line
			(start 0.12065 -0.2794)
			(end -0.12065 -0.2794)
			(stroke
				(width 0.1)
				(type default)
			)
			(layer "B.Fab")
		)
		(fp_line
			(start -0.67945 -0.3048)
			(end -0.67945 0.3048)
			(stroke
				(width 0.1)
				(type default)
			)
			(layer "B.Fab")
		)
		(fp_line
			(start -0.12065 -0.3048)
			(end -0.67945 -0.3048)
			(stroke
				(width 0.1)
				(type default)
			)
			(layer "B.Fab")
		)
		(fp_line
			(start 0.12065 -0.305054)
			(end 0.12065 -0.2794)
			(stroke
				(width 0.1)
				(type default)
			)
			(layer "B.Fab")
		)
		(fp_line
			(start 0.67945 -0.305054)
			(end 0.12065 -0.305054)
			(stroke
				(width 0.1)
				(type default)
			)
			(layer "B.Fab")
		)
		(pad "1" smd circle
			(at 0.40005 0 90)
			(size 0 0)
			(layers "B.Cu" "B.Mask" "B.Paste")
			(net "PVPP_HBM_CPU0_MODE")
		)
		(pad "2" smd circle
			(at -0.40005 0 90)
			(size 0 0)
			(layers "B.Cu" "B.Mask" "B.Paste")
			(net "GND")
		)
	)
	(footprint ""
		(layer "B.Cu")
		(at 103.901494 -252.17628 -90)
		(property "Reference" "C327"
			(at 0 0 90)
			(layer "B.SilkS")
			(hide yes)
			(effects
				(font
					(size 1.27 1.27)
				)
				(justify mirror)
			)
		)
		(property "Value" ""
			(at 0 0 90)
			(layer "B.Fab")
			(effects
				(font
					(size 1.27 1.27)
				)
				(justify mirror)
			)
		)
		(duplicate_pad_numbers_are_jumpers no)
		(fp_line
			(start -1.524 0.762)
			(end 1.524 0.762)
			(stroke
				(width 0.1524)
				(type default)
			)
			(layer "B.SilkS")
		)
		(fp_line
			(start 1.524 0.762)
			(end 1.524 -0.762)
			(stroke
				(width 0.1524)
				(type default)
			)
			(layer "B.SilkS")
		)
		(fp_line
			(start -1.524 -0.762)
			(end -1.524 0.762)
			(stroke
				(width 0.1524)
				(type default)
			)
			(layer "B.SilkS")
		)
		(fp_line
			(start 1.524 -0.762)
			(end -1.524 -0.762)
			(stroke
				(width 0.1524)
				(type default)
			)
			(layer "B.SilkS")
		)
		(fp_line
			(start -1.1049 0.724916)
			(end -1.1049 -0.724916)
			(stroke
				(width 0.1)
				(type default)
			)
			(layer "B.Fab")
		)
		(fp_line
			(start 1.1049 0.724916)
			(end -1.1049 0.724916)
			(stroke
				(width 0.1)
				(type default)
			)
			(layer "B.Fab")
		)
		(fp_line
			(start -1.1049 -0.724916)
			(end 1.1049 -0.724916)
			(stroke
				(width 0.1)
				(type default)
			)
			(layer "B.Fab")
		)
		(fp_line
			(start 1.1049 -0.724916)
			(end 1.1049 0.724916)
			(stroke
				(width 0.1)
				(type default)
			)
			(layer "B.Fab")
		)
		(pad "1" smd rect
			(at 0.889 0 270)
			(size 1.016 1.27)
			(layers "B.Cu" "B.Mask" "B.Paste")
			(net "PVCCIN_CPU1")
		)
		(pad "2" smd rect
			(at -0.889 0 270)
			(size 1.016 1.27)
			(layers "B.Cu" "B.Mask" "B.Paste")
			(net "GND")
		)
	)
	(footprint ""
		(layer "B.Cu")
		(at 53.14188 -171.541948 -90)
		(property "Reference" "PR699"
			(at 0 0 90)
			(layer "B.SilkS")
			(hide yes)
			(effects
				(font
					(size 1.27 1.27)
				)
				(justify mirror)
			)
		)
		(property "Value" ""
			(at 0 0 90)
			(layer "B.Fab")
			(effects
				(font
					(size 1.27 1.27)
				)
				(justify mirror)
			)
		)
		(duplicate_pad_numbers_are_jumpers no)
		(fp_line
			(start -0.7874 0.4064)
			(end 0.7874 0.4064)
			(stroke
				(width 0.1524)
				(type default)
			)
			(layer "B.SilkS")
		)
		(fp_line
			(start 0.7874 0.4064)
			(end 0.7874 -0.4064)
			(stroke
				(width 0.1524)
				(type default)
			)
			(layer "B.SilkS")
		)
		(fp_line
			(start -0.7874 -0.4064)
			(end -0.7874 0.4064)
			(stroke
				(width 0.1524)
				(type default)
			)
			(layer "B.SilkS")
		)
		(fp_line
			(start 0.7874 -0.4064)
			(end -0.7874 -0.4064)
			(stroke
				(width 0.1524)
				(type default)
			)
			(layer "B.SilkS")
		)
		(fp_line
			(start -0.67945 0.3048)
			(end -0.120396 0.3048)
			(stroke
				(width 0.1)
				(type default)
			)
			(layer "B.Fab")
		)
		(fp_line
			(start -0.120396 0.3048)
			(end -0.120396 0.2794)
			(stroke
				(width 0.1)
				(type default)
			)
			(layer "B.Fab")
		)
		(fp_line
			(start 0.12065 0.3048)
			(end 0.67945 0.3048)
			(stroke
				(width 0.1)
				(type default)
			)
			(layer "B.Fab")
		)
		(fp_line
			(start 0.67945 0.3048)
			(end 0.67945 -0.305054)
			(stroke
				(width 0.1)
				(type default)
			)
			(layer "B.Fab")
		)
		(fp_line
			(start -0.120396 0.2794)
			(end 0.12065 0.2794)
			(stroke
				(width 0.1)
				(type default)
			)
			(layer "B.Fab")
		)
		(fp_line
			(start 0.12065 0.2794)
			(end 0.12065 0.3048)
			(stroke
				(width 0.1)
				(type default)
			)
			(layer "B.Fab")
		)
		(fp_line
			(start -0.12065 -0.2794)
			(end -0.12065 -0.3048)
			(stroke
				(width 0.1)
				(type default)
			)
			(layer "B.Fab")
		)
		(fp_line
			(start 0.12065 -0.2794)
			(end -0.12065 -0.2794)
			(stroke
				(width 0.1)
				(type default)
			)
			(layer "B.Fab")
		)
		(fp_line
			(start -0.67945 -0.3048)
			(end -0.67945 0.3048)
			(stroke
				(width 0.1)
				(type default)
			)
			(layer "B.Fab")
		)
		(fp_line
			(start -0.12065 -0.3048)
			(end -0.67945 -0.3048)
			(stroke
				(width 0.1)
				(type default)
			)
			(layer "B.Fab")
		)
		(fp_line
			(start 0.12065 -0.305054)
			(end 0.12065 -0.2794)
			(stroke
				(width 0.1)
				(type default)
			)
			(layer "B.Fab")
		)
		(fp_line
			(start 0.67945 -0.305054)
			(end 0.12065 -0.305054)
			(stroke
				(width 0.1)
				(type default)
			)
			(layer "B.Fab")
		)
		(pad "1" smd circle
			(at 0.40005 0 90)
			(size 0 0)
			(layers "B.Cu" "B.Mask" "B.Paste")
			(net "P3V3")
		)
		(pad "2" smd circle
			(at -0.40005 0 90)
			(size 0 0)
			(layers "B.Cu" "B.Mask" "B.Paste")
			(net "PVCCFA_EHV_CPU1_PVCC")
		)
	)
)
